FILE_TYPE = CONNECTIVITY;
{Allegro Design Entry HDL 17.4-2019 S026 (4007227) 1/17/2022}
"PAGE_NUMBER" = 440;
0"NC";
END.
